(kicad_pcb
	(version 20260206)
	(generator "pcbnew")
	(generator_version "10.0")
	(general
		(thickness 1.6)
		(legacy_teardrops no)
	)
	(paper "A4")
	(title_block
		(title "03242023_DA0F0TMBIJ0_F0T_Motherboard_J_brd_V01_OCP.brd")
		(comment 1 "Grand Teton / footprint 1682 of 6105 (U1), pads 1382-1492 of 4677")
	)
	(layers
		(0 "F.Cu" signal "TOP")
		(4 "In1.Cu" signal "GND")
		(6 "In2.Cu" signal "IN1")
		(8 "In3.Cu" signal "GND1")
		(10 "In4.Cu" signal "IN2")
		(12 "In5.Cu" signal "GND2")
		(14 "In6.Cu" signal "IN3")
		(16 "In7.Cu" signal "GND3")
		(18 "In8.Cu" signal "VCC")
		(20 "In9.Cu" signal "VCC1")
		(22 "In10.Cu" signal "GND4")
		(24 "In11.Cu" signal "IN4")
		(26 "In12.Cu" signal "GND5")
		(28 "In13.Cu" signal "IN5")
		(30 "In14.Cu" signal "GND6")
		(32 "In15.Cu" signal "IN6")
		(34 "In16.Cu" signal "GND7")
		(2 "B.Cu" signal "BOTTOM")
		(9 "F.Adhes" user "F.Adhesive")
		(11 "B.Adhes" user "B.Adhesive")
		(13 "F.Paste" user "Package Geometry/Pastemask Top")
		(15 "B.Paste" user "Package Geometry/Pastemask Bottom")
		(5 "F.SilkS" user "Ref Des/Silkscreen Top")
		(7 "B.SilkS" user "Ref Des/Silkscreen Bottom")
		(1 "F.Mask" user "Board Geometry/Soldermask Top")
		(3 "B.Mask" user "Board Geometry/Soldermask Bottom")
		(17 "Dwgs.User" user "User.Drawings")
		(19 "Cmts.User" user "User.Comments")
		(21 "Eco1.User" user "User.Eco1")
		(23 "Eco2.User" user "User.Eco2")
		(25 "Edge.Cuts" user "Board Geometry/Outline")
		(27 "Margin" user)
		(31 "F.CrtYd" user "Package Geometry/Place Bound Top")
		(29 "B.CrtYd" user "Package Geometry/Place Bound Bottom")
		(35 "F.Fab" user "Ref Des/Assembly Top")
		(33 "B.Fab" user "Ref Des/Assembly Bottom")
	)
	(footprint ""
		(layer "F.Cu")
		(at 111.93018 -251.76988 90)
		(property "Reference" "U1"
			(at -74.913236 41.548812 0)
			(unlocked yes)
			(layer "F.SilkS")
			(effects
				(font
					(size 1.6002 1.1938)
					(thickness 0.1524)
				)
				(justify left)
			)
		)
		(property "Value" ""
			(at 0 0 90)
			(layer "F.Fab")
			(effects
				(font
					(size 1.27 1.27)
				)
			)
		)
		(duplicate_pad_numbers_are_jumpers no)
		(pad "BR25" smd circle
			(at -17.89176 -1.699514 270)
			(size 0.4318 0.4318)
			(layers "F.Cu" "F.Mask" "F.Paste")
			(net "JTAG_DBP_CPU1_QS_GTL_R_TMS")
		)
		(pad "BR27" smd circle
			(at -16.263874 -1.699514 270)
			(size 0.4318 0.4318)
			(layers "F.Cu" "F.Mask" "F.Paste")
			(net "GND")
		)
		(pad "BR29" smd circle
			(at -14.635988 -1.699514 270)
			(size 0.4318 0.4318)
			(layers "F.Cu" "F.Mask" "F.Paste")
			(net "GND")
		)
		(pad "BR31" smd circle
			(at -13.008356 -1.699514 270)
			(size 0.4318 0.4318)
			(layers "F.Cu" "F.Mask" "F.Paste")
			(net "GND")
		)
		(pad "BR33" smd circle
			(at -11.380724 -1.699514 270)
			(size 0.4318 0.4318)
			(layers "F.Cu" "F.Mask" "F.Paste")
			(net "GND")
		)
		(pad "BR35" smd circle
			(at -9.752838 -1.699514 270)
			(size 0.4318 0.4318)
			(layers "F.Cu" "F.Mask" "F.Paste")
			(net "GND")
		)
		(pad "BR37" smd circle
			(at -8.124952 -1.699514 270)
			(size 0.4318 0.4318)
			(layers "F.Cu" "F.Mask" "F.Paste")
			(net "GND")
		)
		(pad "BR39" smd circle
			(at -6.49732 -1.699514 270)
			(size 0.4318 0.4318)
			(layers "F.Cu" "F.Mask" "F.Paste")
			(net "GND")
		)
		(pad "BR41" smd circle
			(at -4.869434 -1.699514 270)
			(size 0.4318 0.4318)
			(layers "F.Cu" "F.Mask" "F.Paste")
			(net "GND")
		)
		(pad "BR43" smd circle
			(at -3.241802 -1.699514 270)
			(size 0.4318 0.4318)
			(layers "F.Cu" "F.Mask" "F.Paste")
			(net "GND")
		)
		(pad "BR45" smd circle
			(at -1.613916 -1.699514 270)
			(size 0.4318 0.4318)
			(layers "F.Cu" "F.Mask" "F.Paste")
			(net "GND")
		)
		(pad "BR48" smd circle
			(at 2.427732 -1.589532 270)
			(size 0.4318 0.4318)
			(layers "F.Cu" "F.Mask" "F.Paste")
			(net "GND")
		)
		(pad "BR50" smd circle
			(at 4.055618 -1.589532 270)
			(size 0.4318 0.4318)
			(layers "F.Cu" "F.Mask" "F.Paste")
			(net "GND")
		)
		(pad "BR52" smd circle
			(at 5.68325 -1.589532 270)
			(size 0.4318 0.4318)
			(layers "F.Cu" "F.Mask" "F.Paste")
			(net "GND")
		)
		(pad "BR54" smd circle
			(at 7.311136 -1.589532 270)
			(size 0.4318 0.4318)
			(layers "F.Cu" "F.Mask" "F.Paste")
			(net "GND")
		)
		(pad "BR56" smd circle
			(at 8.939022 -1.589532 270)
			(size 0.4318 0.4318)
			(layers "F.Cu" "F.Mask" "F.Paste")
			(net "GND")
		)
		(pad "BR58" smd circle
			(at 10.566654 -1.589532 270)
			(size 0.4318 0.4318)
			(layers "F.Cu" "F.Mask" "F.Paste")
			(net "GND")
		)
		(pad "BR60" smd circle
			(at 12.19454 -1.589532 270)
			(size 0.4318 0.4318)
			(layers "F.Cu" "F.Mask" "F.Paste")
			(net "PVCCIN_CPU1")
		)
		(pad "BR62" smd circle
			(at 13.822426 -1.589532 270)
			(size 0.4318 0.4318)
			(layers "F.Cu" "F.Mask" "F.Paste")
			(net "PVCCIN_CPU1")
		)
		(pad "BR64" smd circle
			(at 15.450058 -1.589532 270)
			(size 0.4318 0.4318)
			(layers "F.Cu" "F.Mask" "F.Paste")
			(net "GND")
		)
		(pad "BR66" smd circle
			(at 17.07769 -1.589532 270)
			(size 0.4318 0.4318)
			(layers "F.Cu" "F.Mask" "F.Paste")
			(net "GND")
		)
		(pad "BR68" smd circle
			(at 18.705576 -1.589532 270)
			(size 0.4318 0.4318)
			(layers "F.Cu" "F.Mask" "F.Paste")
			(net "GND")
		)
		(pad "BR70" smd circle
			(at 20.333462 -1.589532 270)
			(size 0.4318 0.4318)
			(layers "F.Cu" "F.Mask" "F.Paste")
			(net "GND")
		)
		(pad "BR72" smd circle
			(at 21.961094 -1.589532 270)
			(size 0.4318 0.4318)
			(layers "F.Cu" "F.Mask" "F.Paste")
			(net "GND")
		)
		(pad "BR74" smd circle
			(at 23.58898 -1.589532 270)
			(size 0.4318 0.4318)
			(layers "F.Cu" "F.Mask" "F.Paste")
			(net "GND")
		)
		(pad "BR76" smd circle
			(at 25.216612 -1.589532 270)
			(size 0.4318 0.4318)
			(layers "F.Cu" "F.Mask" "F.Paste")
			(net "GND")
		)
		(pad "BR78" smd circle
			(at 26.844498 -1.589532 270)
			(size 0.4318 0.4318)
			(layers "F.Cu" "F.Mask" "F.Paste")
			(net "PVCCIN_CPU1")
		)
		(pad "BR80" smd circle
			(at 28.472384 -1.589532 270)
			(size 0.4318 0.4318)
			(layers "F.Cu" "F.Mask" "F.Paste")
			(net "GND")
		)
		(pad "BR82" smd circle
			(at 30.100016 -1.589532 270)
			(size 0.4318 0.4318)
			(layers "F.Cu" "F.Mask" "F.Paste")
			(net "GND")
		)
		(pad "BR84" smd circle
			(at 31.727902 -1.589532 270)
			(size 0.4318 0.4318)
			(layers "F.Cu" "F.Mask" "F.Paste")
			(net "GND")
		)
		(pad "BR86" smd circle
			(at 33.355534 -1.589532 270)
			(size 0.4318 0.4318)
			(layers "F.Cu" "F.Mask" "F.Paste")
			(net "GND")
		)
		(pad "BR88" smd circle
			(at 34.98342 -1.589532 270)
			(size 0.4318 0.4318)
			(layers "F.Cu" "F.Mask" "F.Paste")
			(net "GND")
		)
		(pad "BR90" smd oval
			(at 36.611306 -1.589532)
			(size 0.381 0.4826)
			(drill
				(offset 0 -0.0508)
			)
			(layers "F.Cu" "F.Mask" "F.Paste")
			(net "GND")
		)
		(pad "BT2" smd oval
			(at -36.611306 -1.229614 180)
			(size 0.381 0.4826)
			(drill
				(offset 0 -0.0508)
			)
			(layers "F.Cu" "F.Mask" "F.Paste")
			(net "UPI_CPU1_CPU0_P0P1_DN<23>")
		)
		(pad "BT4" smd circle
			(at -34.98342 -1.229614 270)
			(size 0.4318 0.4318)
			(layers "F.Cu" "F.Mask" "F.Paste")
			(net "GND")
		)
		(pad "BT6" smd circle
			(at -33.355534 -1.229614 270)
			(size 0.4318 0.4318)
			(layers "F.Cu" "F.Mask" "F.Paste")
			(net "UPI_CPU0_CPU1_P1P0_DP<23>")
		)
		(pad "BT8" smd circle
			(at -31.727902 -1.229614 270)
			(size 0.4318 0.4318)
			(layers "F.Cu" "F.Mask" "F.Paste")
			(net "GND")
		)
		(pad "BT10" smd circle
			(at -30.100016 -1.229614 270)
			(size 0.4318 0.4318)
			(layers "F.Cu" "F.Mask" "F.Paste")
			(net "P5E_CPU1_PE1_RX_DP<9>")
		)
		(pad "BT12" smd circle
			(at -28.472384 -1.229614 270)
			(size 0.4318 0.4318)
			(layers "F.Cu" "F.Mask" "F.Paste")
			(net "GND")
		)
		(pad "BT14" smd circle
			(at -26.844498 -1.229614 270)
			(size 0.4318 0.4318)
			(layers "F.Cu" "F.Mask" "F.Paste")
			(net "P5E_CPU1_PE1_TX_DP<9>")
		)
		(pad "BT16" smd circle
			(at -25.216612 -1.229614 270)
			(size 0.4318 0.4318)
			(layers "F.Cu" "F.Mask" "F.Paste")
			(net "GND")
		)
		(pad "BT18" smd circle
			(at -23.58898 -1.229614 270)
			(size 0.4318 0.4318)
			(layers "F.Cu" "F.Mask" "F.Paste")
			(net "TP_DMI_CPU1_PCH_RX_C_DP<7>")
		)
		(pad "BT20" smd circle
			(at -21.961094 -1.229614 270)
			(size 0.4318 0.4318)
			(layers "F.Cu" "F.Mask" "F.Paste")
			(net "GND")
		)
		(pad "BT22" smd circle
			(at -20.333462 -1.229614 270)
			(size 0.4318 0.4318)
			(layers "F.Cu" "F.Mask" "F.Paste")
			(net "I3C_SPD_DDRABCD_CPU1_SCL")
		)
		(pad "BT24" smd circle
			(at -18.705576 -1.229614 270)
			(size 0.4318 0.4318)
			(layers "F.Cu" "F.Mask" "F.Paste")
			(net "JTAG_DBP_CPU1_GTL_R_TCK")
		)
		(pad "BT26" smd circle
			(at -17.07769 -1.229614 270)
			(size 0.4318 0.4318)
			(layers "F.Cu" "F.Mask" "F.Paste")
			(net "PU_CPU1_TXT_AGENT")
		)
		(pad "BT28" smd circle
			(at -15.450058 -1.229614 270)
			(size 0.4318 0.4318)
			(layers "F.Cu" "F.Mask" "F.Paste")
			(net "TP_TRC_CPU1_PTI<9>")
		)
		(pad "BT30" smd circle
			(at -13.822426 -1.229614 270)
			(size 0.4318 0.4318)
			(layers "F.Cu" "F.Mask" "F.Paste")
			(net "TP_TRC_CPU1_PTI<11>")
		)
		(pad "BT32" smd circle
			(at -12.19454 -1.229614 270)
			(size 0.4318 0.4318)
			(layers "F.Cu" "F.Mask" "F.Paste")
			(net "PVCCIN_CPU1")
		)
		(pad "BT34" smd circle
			(at -10.566654 -1.229614 270)
			(size 0.4318 0.4318)
			(layers "F.Cu" "F.Mask" "F.Paste")
			(net "PVCCIN_CPU1")
		)
		(pad "BT36" smd circle
			(at -8.939022 -1.229614 270)
			(size 0.4318 0.4318)
			(layers "F.Cu" "F.Mask" "F.Paste")
			(net "PVCCIN_CPU1")
		)
		(pad "BT38" smd circle
			(at -7.311136 -1.229614 270)
			(size 0.4318 0.4318)
			(layers "F.Cu" "F.Mask" "F.Paste")
			(net "PVCCIN_CPU1")
		)
		(pad "BT40" smd circle
			(at -5.68325 -1.229614 270)
			(size 0.4318 0.4318)
			(layers "F.Cu" "F.Mask" "F.Paste")
			(net "PVCCIN_CPU1")
		)
		(pad "BT42" smd circle
			(at -4.055618 -1.229614 270)
			(size 0.4318 0.4318)
			(layers "F.Cu" "F.Mask" "F.Paste")
			(net "PVCCIN_CPU1")
		)
		(pad "BT44" smd circle
			(at -2.427732 -1.229614 270)
			(size 0.4318 0.4318)
			(layers "F.Cu" "F.Mask" "F.Paste")
			(net "PVCCIN_CPU1")
		)
		(pad "BT47" smd circle
			(at 1.613916 -1.119886 270)
			(size 0.4318 0.4318)
			(layers "F.Cu" "F.Mask" "F.Paste")
			(net "PVCCIN_CPU1")
		)
		(pad "BT49" smd circle
			(at 3.241802 -1.119886 270)
			(size 0.4318 0.4318)
			(layers "F.Cu" "F.Mask" "F.Paste")
			(net "PVCCIN_CPU1")
		)
		(pad "BT51" smd circle
			(at 4.869434 -1.119886 270)
			(size 0.4318 0.4318)
			(layers "F.Cu" "F.Mask" "F.Paste")
			(net "PVCCIN_CPU1")
		)
		(pad "BT53" smd circle
			(at 6.49732 -1.119886 270)
			(size 0.4318 0.4318)
			(layers "F.Cu" "F.Mask" "F.Paste")
			(net "PVCCIN_CPU1")
		)
		(pad "BT55" smd circle
			(at 8.124952 -1.119886 270)
			(size 0.4318 0.4318)
			(layers "F.Cu" "F.Mask" "F.Paste")
			(net "PVCCIN_CPU1")
		)
		(pad "BT57" smd circle
			(at 9.752838 -1.119886 270)
			(size 0.4318 0.4318)
			(layers "F.Cu" "F.Mask" "F.Paste")
			(net "PVCCIN_CPU1")
		)
		(pad "BT59" smd circle
			(at 11.380724 -1.119886 270)
			(size 0.4318 0.4318)
			(layers "F.Cu" "F.Mask" "F.Paste")
			(net "PVCCIN_CPU1")
		)
		(pad "BT61" smd circle
			(at 13.008356 -1.119886 270)
			(size 0.4318 0.4318)
			(layers "F.Cu" "F.Mask" "F.Paste")
			(net "PVCCIN_CPU1")
		)
		(pad "BT63" smd circle
			(at 14.635988 -1.119886 270)
			(size 0.4318 0.4318)
			(layers "F.Cu" "F.Mask" "F.Paste")
			(net "PVCCIN_CPU1")
		)
		(pad "BT65" smd circle
			(at 16.263874 -1.119886 270)
			(size 0.4318 0.4318)
			(layers "F.Cu" "F.Mask" "F.Paste")
			(net "PVCCIN_CPU1")
		)
		(pad "BT67" smd circle
			(at 17.89176 -1.119886 270)
			(size 0.4318 0.4318)
			(layers "F.Cu" "F.Mask" "F.Paste")
			(net "PVCCIN_CPU1")
		)
		(pad "BT69" smd circle
			(at 19.519392 -1.119886 270)
			(size 0.4318 0.4318)
			(layers "F.Cu" "F.Mask" "F.Paste")
			(net "PVCCIN_CPU1")
		)
		(pad "BT71" smd circle
			(at 21.147278 -1.119886 270)
			(size 0.4318 0.4318)
			(layers "F.Cu" "F.Mask" "F.Paste")
			(net "PVCCIN_CPU1")
		)
		(pad "BT73" smd circle
			(at 22.77491 -1.119886 270)
			(size 0.4318 0.4318)
			(layers "F.Cu" "F.Mask" "F.Paste")
			(net "PVCCIN_CPU1")
		)
		(pad "BT75" smd circle
			(at 24.402796 -1.119886 270)
			(size 0.4318 0.4318)
			(layers "F.Cu" "F.Mask" "F.Paste")
			(net "PVCCIN_CPU1")
		)
		(pad "BT77" smd circle
			(at 26.030682 -1.119886 270)
			(size 0.4318 0.4318)
			(layers "F.Cu" "F.Mask" "F.Paste")
			(net "PVCCIN_CPU1")
		)
		(pad "BT79" smd circle
			(at 27.658314 -1.119886 270)
			(size 0.4318 0.4318)
			(layers "F.Cu" "F.Mask" "F.Paste")
			(net "PVCCIN_CPU1")
		)
		(pad "BT81" smd circle
			(at 29.2862 -1.119886 270)
			(size 0.4318 0.4318)
			(layers "F.Cu" "F.Mask" "F.Paste")
			(net "PVCCIN_CPU1")
		)
		(pad "BT83" smd circle
			(at 30.914086 -1.119886 270)
			(size 0.4318 0.4318)
			(layers "F.Cu" "F.Mask" "F.Paste")
			(net "PVCCIN_CPU1")
		)
		(pad "BT85" smd circle
			(at 32.541718 -1.119886 270)
			(size 0.4318 0.4318)
			(layers "F.Cu" "F.Mask" "F.Paste")
			(net "PVCCIN_CPU1")
		)
		(pad "BT87" smd circle
			(at 34.169604 -1.119886 270)
			(size 0.4318 0.4318)
			(layers "F.Cu" "F.Mask" "F.Paste")
			(net "PVCCIN_CPU1")
		)
		(pad "BT89" smd circle
			(at 35.797236 -1.119886 270)
			(size 0.4318 0.4318)
			(layers "F.Cu" "F.Mask" "F.Paste")
			(net "PVCCIN_CPU1")
		)
		(pad "BU3" smd circle
			(at -35.797236 -0.759714 270)
			(size 0.4318 0.4318)
			(layers "F.Cu" "F.Mask" "F.Paste")
			(net "UPI_CPU1_CPU0_P0P1_DP<23>")
		)
		(pad "BU5" smd circle
			(at -34.169604 -0.759714 270)
			(size 0.4318 0.4318)
			(layers "F.Cu" "F.Mask" "F.Paste")
			(net "UPI_CPU0_CPU1_P1P0_DN<23>")
		)
		(pad "BU7" smd circle
			(at -32.541718 -0.759714 270)
			(size 0.4318 0.4318)
			(layers "F.Cu" "F.Mask" "F.Paste")
			(net "GND")
		)
		(pad "BU9" smd circle
			(at -30.914086 -0.759714 270)
			(size 0.4318 0.4318)
			(layers "F.Cu" "F.Mask" "F.Paste")
			(net "P5E_CPU1_PE1_RX_DP<8>")
		)
		(pad "BU11" smd circle
			(at -29.2862 -0.759714 270)
			(size 0.4318 0.4318)
			(layers "F.Cu" "F.Mask" "F.Paste")
			(net "VSENSE_PVCCD_HV_CPU1_DP")
		)
		(pad "BU13" smd circle
			(at -27.658314 -0.759714 270)
			(size 0.4318 0.4318)
			(layers "F.Cu" "F.Mask" "F.Paste")
			(net "P5E_CPU1_PE1_TX_DN<9>")
		)
		(pad "BU15" smd circle
			(at -26.030682 -0.759714 270)
			(size 0.4318 0.4318)
			(layers "F.Cu" "F.Mask" "F.Paste")
			(net "GND")
		)
		(pad "BU17" smd circle
			(at -24.402796 -0.759714 270)
			(size 0.4318 0.4318)
			(layers "F.Cu" "F.Mask" "F.Paste")
			(net "TP_DMI_CPU1_PCH_RX_C_DN<7>")
		)
		(pad "BU19" smd circle
			(at -22.77491 -0.759714 270)
			(size 0.4318 0.4318)
			(layers "F.Cu" "F.Mask" "F.Paste")
			(net "GND")
		)
		(pad "BU21" smd circle
			(at -21.147278 -0.759714 270)
			(size 0.4318 0.4318)
			(layers "F.Cu" "F.Mask" "F.Paste")
			(net "GND")
		)
		(pad "BU23" smd circle
			(at -19.519392 -0.759714 270)
			(size 0.4318 0.4318)
			(layers "F.Cu" "F.Mask" "F.Paste")
			(net "GND")
		)
		(pad "BU25" smd circle
			(at -17.89176 -0.759714 270)
			(size 0.4318 0.4318)
			(layers "F.Cu" "F.Mask" "F.Paste")
			(net "GND")
		)
		(pad "BU27" smd circle
			(at -16.263874 -0.759714 270)
			(size 0.4318 0.4318)
			(layers "F.Cu" "F.Mask" "F.Paste")
			(net "TP_TRC_CPU1_PTI<8>")
		)
		(pad "BU29" smd circle
			(at -14.635988 -0.759714 270)
			(size 0.4318 0.4318)
			(layers "F.Cu" "F.Mask" "F.Paste")
			(net "TP_TRC_CPU1_PTI<10>")
		)
		(pad "BU31" smd circle
			(at -13.008356 -0.759714 270)
			(size 0.4318 0.4318)
			(layers "F.Cu" "F.Mask" "F.Paste")
			(net "GND")
		)
		(pad "BU33" smd circle
			(at -11.380724 -0.759714 270)
			(size 0.4318 0.4318)
			(layers "F.Cu" "F.Mask" "F.Paste")
			(net "PVCCIN_CPU1")
		)
		(pad "BU35" smd circle
			(at -9.752838 -0.759714 270)
			(size 0.4318 0.4318)
			(layers "F.Cu" "F.Mask" "F.Paste")
			(net "PVCCIN_CPU1")
		)
		(pad "BU37" smd circle
			(at -8.124952 -0.759714 270)
			(size 0.4318 0.4318)
			(layers "F.Cu" "F.Mask" "F.Paste")
			(net "PVCCIN_CPU1")
		)
		(pad "BU39" smd circle
			(at -6.49732 -0.759714 270)
			(size 0.4318 0.4318)
			(layers "F.Cu" "F.Mask" "F.Paste")
			(net "PVCCIN_CPU1")
		)
		(pad "BU41" smd circle
			(at -4.869434 -0.759714 270)
			(size 0.4318 0.4318)
			(layers "F.Cu" "F.Mask" "F.Paste")
			(net "PVCCIN_CPU1")
		)
		(pad "BU43" smd circle
			(at -3.241802 -0.759714 270)
			(size 0.4318 0.4318)
			(layers "F.Cu" "F.Mask" "F.Paste")
			(net "PVCCIN_CPU1")
		)
		(pad "BU45" smd circle
			(at -1.613916 -0.759714 270)
			(size 0.4318 0.4318)
			(layers "F.Cu" "F.Mask" "F.Paste")
			(net "PVCCIN_CPU1")
		)
		(pad "BU48" smd circle
			(at 2.427732 -0.649732 270)
			(size 0.4318 0.4318)
			(layers "F.Cu" "F.Mask" "F.Paste")
			(net "PVCCIN_CPU1")
		)
		(pad "BU50" smd circle
			(at 4.055618 -0.649732 270)
			(size 0.4318 0.4318)
			(layers "F.Cu" "F.Mask" "F.Paste")
			(net "PVCCIN_CPU1")
		)
		(pad "BU52" smd circle
			(at 5.68325 -0.649732 270)
			(size 0.4318 0.4318)
			(layers "F.Cu" "F.Mask" "F.Paste")
			(net "PVCCIN_CPU1")
		)
		(pad "BU54" smd circle
			(at 7.311136 -0.649732 270)
			(size 0.4318 0.4318)
			(layers "F.Cu" "F.Mask" "F.Paste")
			(net "PVCCIN_CPU1")
		)
		(pad "BU56" smd circle
			(at 8.939022 -0.649732 270)
			(size 0.4318 0.4318)
			(layers "F.Cu" "F.Mask" "F.Paste")
			(net "PVCCIN_CPU1")
		)
		(pad "BU58" smd circle
			(at 10.566654 -0.649732 270)
			(size 0.4318 0.4318)
			(layers "F.Cu" "F.Mask" "F.Paste")
			(net "PVCCIN_CPU1")
		)
		(pad "BU60" smd circle
			(at 12.19454 -0.649732 270)
			(size 0.4318 0.4318)
			(layers "F.Cu" "F.Mask" "F.Paste")
			(net "PVCCIN_CPU1")
		)
		(pad "BU62" smd circle
			(at 13.822426 -0.649732 270)
			(size 0.4318 0.4318)
			(layers "F.Cu" "F.Mask" "F.Paste")
			(net "PVCCIN_CPU1")
		)
		(pad "BU64" smd circle
			(at 15.450058 -0.649732 270)
			(size 0.4318 0.4318)
			(layers "F.Cu" "F.Mask" "F.Paste")
			(net "PVCCIN_CPU1")
		)
		(pad "BU66" smd circle
			(at 17.07769 -0.649732 270)
			(size 0.4318 0.4318)
			(layers "F.Cu" "F.Mask" "F.Paste")
			(net "PVCCIN_CPU1")
		)
		(pad "BU68" smd circle
			(at 18.705576 -0.649732 270)
			(size 0.4318 0.4318)
			(layers "F.Cu" "F.Mask" "F.Paste")
			(net "PVCCIN_CPU1")
		)
		(pad "BU70" smd circle
			(at 20.333462 -0.649732 270)
			(size 0.4318 0.4318)
			(layers "F.Cu" "F.Mask" "F.Paste")
			(net "PVCCIN_CPU1")
		)
	)
)
